# S9S_MB_2U (Grand Teton) — schematic netlist excerpt (pin names and nets, part order shuffled) for the footprints in the layout excerpt that follows; sources: Cadence DE-HDL packaged netlist, KiCad conversion of 03242023_DA0F0TMBIJ0_F0T_Motherboard_J_brd_V01_OCP.brd

C2038  Q_CAP  10UF 6.3V 20% X6S  pkg C0402  page 152 : A = P3V3_AUX_USB_HUB ; B = GND
PC1180_P0_4  Q_CAP  22UF 16V 20% X6S  pkg C0805  page 272 : A = SW_P12V_PVCCFA_EHV_FIVRA_CPU0_L ; B = GND
PC404_P1_2  Q_CAP  22UF 16V 20% X6S  pkg C0805  page 289 : A = SW_P12V_PVCCFA_EHV_FIVRA_CPU1_L ; B = GND

(kicad_pcb
	(version 20260206)
	(generator "pcbnew")
	(generator_version "10.0")
	(general
		(thickness 1.6)
		(legacy_teardrops no)
	)
	(paper "A4")
	(title_block
		(title "03242023_DA0F0TMBIJ0_F0T_Motherboard_J_brd_V01_OCP.brd")
		(comment 1 "Grand Teton / footprints 5797-5799 of 6105")
	)
	(layers
		(0 "F.Cu" signal "TOP")
		(4 "In1.Cu" signal "GND")
		(6 "In2.Cu" signal "IN1")
		(8 "In3.Cu" signal "GND1")
		(10 "In4.Cu" signal "IN2")
		(12 "In5.Cu" signal "GND2")
		(14 "In6.Cu" signal "IN3")
		(16 "In7.Cu" signal "GND3")
		(18 "In8.Cu" signal "VCC")
		(20 "In9.Cu" signal "VCC1")
		(22 "In10.Cu" signal "GND4")
		(24 "In11.Cu" signal "IN4")
		(26 "In12.Cu" signal "GND5")
		(28 "In13.Cu" signal "IN5")
		(30 "In14.Cu" signal "GND6")
		(32 "In15.Cu" signal "IN6")
		(34 "In16.Cu" signal "GND7")
		(2 "B.Cu" signal "BOTTOM")
		(9 "F.Adhes" user "F.Adhesive")
		(11 "B.Adhes" user "B.Adhesive")
		(13 "F.Paste" user "Package Geometry/Pastemask Top")
		(15 "B.Paste" user "Package Geometry/Pastemask Bottom")
		(5 "F.SilkS" user "Ref Des/Silkscreen Top")
		(7 "B.SilkS" user "Ref Des/Silkscreen Bottom")
		(1 "F.Mask" user "Board Geometry/Soldermask Top")
		(3 "B.Mask" user "Board Geometry/Soldermask Bottom")
		(17 "Dwgs.User" user "User.Drawings")
		(19 "Cmts.User" user "User.Comments")
		(21 "Eco1.User" user "User.Eco1")
		(23 "Eco2.User" user "User.Eco2")
		(25 "Edge.Cuts" user "Board Geometry/Outline")
		(27 "Margin" user)
		(31 "F.CrtYd" user "Package Geometry/Place Bound Top")
		(29 "B.CrtYd" user "Package Geometry/Place Bound Bottom")
		(35 "F.Fab" user "Ref Des/Assembly Top")
		(33 "B.Fab" user "Ref Des/Assembly Bottom")
	)
	(footprint ""
		(layer "B.Cu")
		(at 289.907726 -362.795058 90)
		(property "Reference" "PC1180_P0_4"
			(at 0 0 90)
			(layer "B.SilkS")
			(hide yes)
			(effects
				(font
					(size 1.27 1.27)
				)
				(justify mirror)
			)
		)
		(property "Value" ""
			(at 0 0 90)
			(layer "B.Fab")
			(effects
				(font
					(size 1.27 1.27)
				)
				(justify mirror)
			)
		)
		(duplicate_pad_numbers_are_jumpers no)
		(fp_line
			(start 1.524 -0.762)
			(end -1.524 -0.762)
			(stroke
				(width 0.1524)
				(type default)
			)
			(layer "B.SilkS")
		)
		(fp_line
			(start -1.524 -0.762)
			(end -1.524 0.762)
			(stroke
				(width 0.1524)
				(type default)
			)
			(layer "B.SilkS")
		)
		(fp_line
			(start 1.524 0.762)
			(end 1.524 -0.762)
			(stroke
				(width 0.1524)
				(type default)
			)
			(layer "B.SilkS")
		)
		(fp_line
			(start -1.524 0.762)
			(end 1.524 0.762)
			(stroke
				(width 0.1524)
				(type default)
			)
			(layer "B.SilkS")
		)
		(fp_line
			(start 1.1049 -0.724916)
			(end 1.1049 0.724916)
			(stroke
				(width 0.1)
				(type default)
			)
			(layer "B.Fab")
		)
		(fp_line
			(start -1.1049 -0.724916)
			(end 1.1049 -0.724916)
			(stroke
				(width 0.1)
				(type default)
			)
			(layer "B.Fab")
		)
		(fp_line
			(start 1.1049 0.724916)
			(end -1.1049 0.724916)
			(stroke
				(width 0.1)
				(type default)
			)
			(layer "B.Fab")
		)
		(fp_line
			(start -1.1049 0.724916)
			(end -1.1049 -0.724916)
			(stroke
				(width 0.1)
				(type default)
			)
			(layer "B.Fab")
		)
		(pad "1" smd rect
			(at 0.889 0 90)
			(size 1.016 1.27)
			(layers "B.Cu" "B.Mask" "B.Paste")
			(net "SW_P12V_PVCCFA_EHV_FIVRA_CPU0_L")
		)
		(pad "2" smd rect
			(at -0.889 0 90)
			(size 1.016 1.27)
			(layers "B.Cu" "B.Mask" "B.Paste")
			(net "GND")
		)
	)
	(footprint ""
		(layer "B.Cu")
		(at 16.207994 -99.842066)
		(property "Reference" "C2038"
			(at 0 0 0)
			(layer "B.SilkS")
			(hide yes)
			(effects
				(font
					(size 1.27 1.27)
				)
				(justify mirror)
			)
		)
		(property "Value" ""
			(at 0 0 0)
			(layer "B.Fab")
			(effects
				(font
					(size 1.27 1.27)
				)
				(justify mirror)
			)
		)
		(duplicate_pad_numbers_are_jumpers no)
		(fp_line
			(start -0.7874 -0.4064)
			(end -0.7874 0.4064)
			(stroke
				(width 0.1524)
				(type default)
			)
			(layer "B.SilkS")
		)
		(fp_line
			(start -0.7874 0.4064)
			(end 0.7874 0.4064)
			(stroke
				(width 0.1524)
				(type default)
			)
			(layer "B.SilkS")
		)
		(fp_line
			(start 0.7874 -0.4064)
			(end -0.7874 -0.4064)
			(stroke
				(width 0.1524)
				(type default)
			)
			(layer "B.SilkS")
		)
		(fp_line
			(start 0.7874 0.4064)
			(end 0.7874 -0.4064)
			(stroke
				(width 0.1524)
				(type default)
			)
			(layer "B.SilkS")
		)
		(fp_line
			(start -0.67945 -0.3048)
			(end -0.67945 0.3048)
			(stroke
				(width 0.1)
				(type default)
			)
			(layer "B.Fab")
		)
		(fp_line
			(start -0.67945 0.3048)
			(end -0.120396 0.3048)
			(stroke
				(width 0.1)
				(type default)
			)
			(layer "B.Fab")
		)
		(fp_line
			(start -0.12065 -0.3048)
			(end -0.67945 -0.3048)
			(stroke
				(width 0.1)
				(type default)
			)
			(layer "B.Fab")
		)
		(fp_line
			(start -0.12065 -0.2794)
			(end -0.12065 -0.3048)
			(stroke
				(width 0.1)
				(type default)
			)
			(layer "B.Fab")
		)
		(fp_line
			(start -0.120396 0.2794)
			(end 0.12065 0.2794)
			(stroke
				(width 0.1)
				(type default)
			)
			(layer "B.Fab")
		)
		(fp_line
			(start -0.120396 0.3048)
			(end -0.120396 0.2794)
			(stroke
				(width 0.1)
				(type default)
			)
			(layer "B.Fab")
		)
		(fp_line
			(start 0.12065 -0.305054)
			(end 0.12065 -0.2794)
			(stroke
				(width 0.1)
				(type default)
			)
			(layer "B.Fab")
		)
		(fp_line
			(start 0.12065 -0.2794)
			(end -0.12065 -0.2794)
			(stroke
				(width 0.1)
				(type default)
			)
			(layer "B.Fab")
		)
		(fp_line
			(start 0.12065 0.2794)
			(end 0.12065 0.3048)
			(stroke
				(width 0.1)
				(type default)
			)
			(layer "B.Fab")
		)
		(fp_line
			(start 0.12065 0.3048)
			(end 0.67945 0.3048)
			(stroke
				(width 0.1)
				(type default)
			)
			(layer "B.Fab")
		)
		(fp_line
			(start 0.67945 -0.305054)
			(end 0.12065 -0.305054)
			(stroke
				(width 0.1)
				(type default)
			)
			(layer "B.Fab")
		)
		(fp_line
			(start 0.67945 0.3048)
			(end 0.67945 -0.305054)
			(stroke
				(width 0.1)
				(type default)
			)
			(layer "B.Fab")
		)
		(pad "1" smd circle
			(at 0.40005 0 180)
			(size 0 0)
			(layers "B.Cu" "B.Mask" "B.Paste")
			(net "P3V3_AUX_USB_HUB")
		)
		(pad "2" smd circle
			(at -0.40005 0 180)
			(size 0 0)
			(layers "B.Cu" "B.Mask" "B.Paste")
			(net "GND")
		)
	)
	(footprint ""
		(layer "B.Cu")
		(at 52.375054 -353.567492 90)
		(property "Reference" "PC404_P1_2"
			(at 0 0 90)
			(layer "B.SilkS")
			(hide yes)
			(effects
				(font
					(size 1.27 1.27)
				)
				(justify mirror)
			)
		)
		(property "Value" ""
			(at 0 0 90)
			(layer "B.Fab")
			(effects
				(font
					(size 1.27 1.27)
				)
				(justify mirror)
			)
		)
		(duplicate_pad_numbers_are_jumpers no)
		(fp_line
			(start 1.524 -0.762)
			(end -1.524 -0.762)
			(stroke
				(width 0.1524)
				(type default)
			)
			(layer "B.SilkS")
		)
		(fp_line
			(start -1.524 -0.762)
			(end -1.524 0.762)
			(stroke
				(width 0.1524)
				(type default)
			)
			(layer "B.SilkS")
		)
		(fp_line
			(start 1.524 0.762)
			(end 1.524 -0.762)
			(stroke
				(width 0.1524)
				(type default)
			)
			(layer "B.SilkS")
		)
		(fp_line
			(start -1.524 0.762)
			(end 1.524 0.762)
			(stroke
				(width 0.1524)
				(type default)
			)
			(layer "B.SilkS")
		)
		(fp_line
			(start 1.1049 -0.724916)
			(end 1.1049 0.724916)
			(stroke
				(width 0.1)
				(type default)
			)
			(layer "B.Fab")
		)
		(fp_line
			(start -1.1049 -0.724916)
			(end 1.1049 -0.724916)
			(stroke
				(width 0.1)
				(type default)
			)
			(layer "B.Fab")
		)
		(fp_line
			(start 1.1049 0.724916)
			(end -1.1049 0.724916)
			(stroke
				(width 0.1)
				(type default)
			)
			(layer "B.Fab")
		)
		(fp_line
			(start -1.1049 0.724916)
			(end -1.1049 -0.724916)
			(stroke
				(width 0.1)
				(type default)
			)
			(layer "B.Fab")
		)
		(pad "1" smd rect
			(at 0.889 0 90)
			(size 1.016 1.27)
			(layers "B.Cu" "B.Mask" "B.Paste")
			(net "SW_P12V_PVCCFA_EHV_FIVRA_CPU1_L")
		)
		(pad "2" smd rect
			(at -0.889 0 90)
			(size 1.016 1.27)
			(layers "B.Cu" "B.Mask" "B.Paste")
			(net "GND")
		)
	)
)
